(kicad_pcb
	(version 20260206)
	(generator "pcbnew")
	(generator_version "10.0")
	(general
		(thickness 1.6)
		(legacy_teardrops no)
	)
	(paper "A4")
	(title_block
		(title "01162023_DA0F0TEBIF0_F0T_Expander_BD_F_brd_V02_OCP.brd")
		(comment 1 "Grand Teton / footprints 8262-8269 of 9728")
	)
	(layers
		(0 "F.Cu" signal "TOP")
		(4 "In1.Cu" signal "GND")
		(6 "In2.Cu" signal "VCC")
		(8 "In3.Cu" signal "VCC1")
		(10 "In4.Cu" signal "GND1")
		(12 "In5.Cu" signal "IN1")
		(14 "In6.Cu" signal "GND2")
		(16 "In7.Cu" signal "IN2")
		(18 "In8.Cu" signal "GND3")
		(20 "In9.Cu" signal "IN3")
		(22 "In10.Cu" signal "GND4")
		(24 "In11.Cu" signal "IN4")
		(26 "In12.Cu" signal "GND5")
		(28 "In13.Cu" signal "IN5")
		(30 "In14.Cu" signal "GND6")
		(32 "In15.Cu" signal "IN6")
		(34 "In16.Cu" signal "GND7")
		(2 "B.Cu" signal "BOTTOM")
		(9 "F.Adhes" user "F.Adhesive")
		(11 "B.Adhes" user "B.Adhesive")
		(13 "F.Paste" user "Package Geometry/Pastemask Top")
		(15 "B.Paste" user "Package Geometry/Pastemask Bottom")
		(5 "F.SilkS" user "Ref Des/Silkscreen Top")
		(7 "B.SilkS" user "Ref Des/Silkscreen Bottom")
		(1 "F.Mask" user "Board Geometry/Soldermask Top")
		(3 "B.Mask" user "Board Geometry/Soldermask Bottom")
		(17 "Dwgs.User" user "User.Drawings")
		(19 "Cmts.User" user "User.Comments")
		(21 "Eco1.User" user "User.Eco1")
		(23 "Eco2.User" user "User.Eco2")
		(25 "Edge.Cuts" user "Board Geometry/Outline")
		(27 "Margin" user)
		(31 "F.CrtYd" user "Package Geometry/Place Bound Top")
		(29 "B.CrtYd" user "Package Geometry/Place Bound Bottom")
		(35 "F.Fab" user "Ref Des/Assembly Top")
		(33 "B.Fab" user "Ref Des/Assembly Bottom")
	)
	(footprint ""
		(layer "B.Cu")
		(at 178.124866 -297.79976 90)
		(property "Reference" "C1410"
			(at 0 0 90)
			(layer "B.SilkS")
			(hide yes)
			(effects
				(font
					(size 1.27 1.27)
				)
				(justify mirror)
			)
		)
		(property "Value" ""
			(at 0 0 90)
			(layer "B.Fab")
			(effects
				(font
					(size 1.27 1.27)
				)
				(justify mirror)
			)
		)
		(duplicate_pad_numbers_are_jumpers no)
		(fp_line
			(start 0.299974 -0.150114)
			(end -0.299974 -0.150114)
			(stroke
				(width 0.1)
				(type default)
			)
			(layer "B.Fab")
		)
		(fp_line
			(start -0.299974 -0.150114)
			(end -0.299974 0.150114)
			(stroke
				(width 0.1)
				(type default)
			)
			(layer "B.Fab")
		)
		(fp_line
			(start 0.299974 0.150114)
			(end 0.299974 -0.150114)
			(stroke
				(width 0.1)
				(type default)
			)
			(layer "B.Fab")
		)
		(fp_line
			(start -0.299974 0.150114)
			(end 0.299974 0.150114)
			(stroke
				(width 0.1)
				(type default)
			)
			(layer "B.Fab")
		)
		(pad "1" smd rect
			(at 0.2667 0 270)
			(size 0.3048 0.381)
			(layers "B.Cu" "B.Mask" "B.Paste")
			(net "P0V8_PEX1")
		)
		(pad "2" smd rect
			(at -0.2667 0 270)
			(size 0.3048 0.381)
			(layers "B.Cu" "B.Mask" "B.Paste")
			(net "GND")
		)
	)
	(footprint ""
		(layer "B.Cu")
		(at 331.305154 -216.203022)
		(property "Reference" "C2077"
			(at 0 0 0)
			(layer "B.SilkS")
			(hide yes)
			(effects
				(font
					(size 1.27 1.27)
				)
				(justify mirror)
			)
		)
		(property "Value" ""
			(at 0 0 0)
			(layer "B.Fab")
			(effects
				(font
					(size 1.27 1.27)
				)
				(justify mirror)
			)
		)
		(duplicate_pad_numbers_are_jumpers no)
		(fp_line
			(start -0.69215 -0.2921)
			(end -0.69215 0.2921)
			(stroke
				(width 0.1524)
				(type default)
			)
			(layer "B.SilkS")
		)
		(fp_line
			(start -0.69215 0.2921)
			(end 0.69215 0.2921)
			(stroke
				(width 0.1524)
				(type default)
			)
			(layer "B.SilkS")
		)
		(fp_line
			(start 0.69215 -0.2921)
			(end -0.69215 -0.2921)
			(stroke
				(width 0.1524)
				(type default)
			)
			(layer "B.SilkS")
		)
		(fp_line
			(start 0.69215 0.2921)
			(end 0.69215 -0.2921)
			(stroke
				(width 0.1524)
				(type default)
			)
			(layer "B.SilkS")
		)
		(fp_line
			(start -0.51435 -0.2794)
			(end -0.51435 0.2794)
			(stroke
				(width 0.1)
				(type default)
			)
			(layer "B.Fab")
		)
		(fp_line
			(start -0.51435 0.2794)
			(end 0.51435 0.2794)
			(stroke
				(width 0.1)
				(type default)
			)
			(layer "B.Fab")
		)
		(fp_line
			(start 0.51435 -0.2794)
			(end -0.51435 -0.2794)
			(stroke
				(width 0.1)
				(type default)
			)
			(layer "B.Fab")
		)
		(fp_line
			(start 0.51435 0.2794)
			(end 0.51435 -0.2794)
			(stroke
				(width 0.1)
				(type default)
			)
			(layer "B.Fab")
		)
		(pad "1" smd circle
			(at 0.40005 0 180)
			(size 0 0)
			(layers "B.Cu" "B.Mask" "B.Paste")
			(net "P3V3_FPGA_VCCIO3")
		)
		(pad "2" smd circle
			(at -0.40005 0 180)
			(size 0 0)
			(layers "B.Cu" "B.Mask" "B.Paste")
			(net "GND")
		)
		(zone
			(layer "B.Cu")
			(hatch none 0.5)
			(connect_pads
				(clearance 0)
			)
			(min_thickness 0.25)
			(keepout
				(tracks not_allowed)
				(vias allowed)
				(pads allowed)
				(copperpour not_allowed)
				(footprints allowed)
			)
			(placement
				(enabled no)
				(sheetname "")
			)
			(fill
				(thermal_gap 0.5)
				(thermal_bridge_width 0.5)
				(island_removal_mode 0)
			)
			(polygon
				(pts
					(xy 331.495654 -216.115392) (xy 331.404214 -216.057226) (xy 331.204824 -216.057226) (xy 331.114654 -216.115392)
					(xy 331.114654 -216.290652) (xy 331.204824 -216.349072) (xy 331.404214 -216.349072) (xy 331.495654 -216.290906)
				)
			)
		)
	)
	(footprint ""
		(layer "B.Cu")
		(at 114.41938 -308.580028 90)
		(property "Reference" "C1158"
			(at 0 0 90)
			(layer "B.SilkS")
			(hide yes)
			(effects
				(font
					(size 1.27 1.27)
				)
				(justify mirror)
			)
		)
		(property "Value" ""
			(at 0 0 90)
			(layer "B.Fab")
			(effects
				(font
					(size 1.27 1.27)
				)
				(justify mirror)
			)
		)
		(duplicate_pad_numbers_are_jumpers no)
		(fp_line
			(start 1.2954 -0.5842)
			(end -1.2954 -0.5842)
			(stroke
				(width 0.1524)
				(type default)
			)
			(layer "B.SilkS")
		)
		(fp_line
			(start -1.2954 -0.5842)
			(end -1.2954 0.5842)
			(stroke
				(width 0.1524)
				(type default)
			)
			(layer "B.SilkS")
		)
		(fp_line
			(start 1.2954 0.5842)
			(end 1.2954 -0.5842)
			(stroke
				(width 0.1524)
				(type default)
			)
			(layer "B.SilkS")
		)
		(fp_line
			(start -1.2954 0.5842)
			(end 1.2954 0.5842)
			(stroke
				(width 0.1524)
				(type default)
			)
			(layer "B.SilkS")
		)
		(fp_line
			(start 0.8636 -0.4572)
			(end -0.8636 -0.4572)
			(stroke
				(width 0.1)
				(type default)
			)
			(layer "B.Fab")
		)
		(fp_line
			(start -0.8636 -0.4572)
			(end -0.8636 -0.4064)
			(stroke
				(width 0.1)
				(type default)
			)
			(layer "B.Fab")
		)
		(fp_line
			(start 1.1938 -0.4064)
			(end 0.8636 -0.4064)
			(stroke
				(width 0.1)
				(type default)
			)
			(layer "B.Fab")
		)
		(fp_line
			(start 0.8636 -0.4064)
			(end 0.8636 -0.4572)
			(stroke
				(width 0.1)
				(type default)
			)
			(layer "B.Fab")
		)
		(fp_line
			(start -0.8636 -0.4064)
			(end -1.1938 -0.4064)
			(stroke
				(width 0.1)
				(type default)
			)
			(layer "B.Fab")
		)
		(fp_line
			(start -1.1938 -0.4064)
			(end -1.1938 0.4064)
			(stroke
				(width 0.1)
				(type default)
			)
			(layer "B.Fab")
		)
		(fp_line
			(start 1.1938 0.4064)
			(end 1.1938 -0.4064)
			(stroke
				(width 0.1)
				(type default)
			)
			(layer "B.Fab")
		)
		(fp_line
			(start 0.8636 0.4064)
			(end 1.1938 0.4064)
			(stroke
				(width 0.1)
				(type default)
			)
			(layer "B.Fab")
		)
		(fp_line
			(start -0.8636 0.4064)
			(end -0.8636 0.4572)
			(stroke
				(width 0.1)
				(type default)
			)
			(layer "B.Fab")
		)
		(fp_line
			(start -1.1938 0.4064)
			(end -0.8636 0.4064)
			(stroke
				(width 0.1)
				(type default)
			)
			(layer "B.Fab")
		)
		(fp_line
			(start 0.8636 0.4572)
			(end 0.8636 0.4064)
			(stroke
				(width 0.1)
				(type default)
			)
			(layer "B.Fab")
		)
		(fp_line
			(start -0.8636 0.4572)
			(end 0.8636 0.4572)
			(stroke
				(width 0.1)
				(type default)
			)
			(layer "B.Fab")
		)
		(pad "1" smd rect
			(at 0.7366 0)
			(size 0.7112 0.8128)
			(layers "B.Cu" "B.Mask" "B.Paste")
			(net "P0V8_SERDES_VDDA_PEX0")
		)
		(pad "2" smd rect
			(at -0.7366 0)
			(size 0.7112 0.8128)
			(layers "B.Cu" "B.Mask" "B.Paste")
			(net "GND")
		)
	)
	(footprint ""
		(layer "B.Cu")
		(at 113.514124 -329.44943 180)
		(property "Reference" "R1221"
			(at 0 0 0)
			(layer "B.SilkS")
			(hide yes)
			(effects
				(font
					(size 1.27 1.27)
				)
				(justify mirror)
			)
		)
		(property "Value" ""
			(at 0 0 0)
			(layer "B.Fab")
			(effects
				(font
					(size 1.27 1.27)
				)
				(justify mirror)
			)
		)
		(duplicate_pad_numbers_are_jumpers no)
		(fp_line
			(start 0.7874 0.4064)
			(end 0.7874 -0.4064)
			(stroke
				(width 0.1524)
				(type default)
			)
			(layer "B.SilkS")
		)
		(fp_line
			(start 0.7874 -0.4064)
			(end -0.7874 -0.4064)
			(stroke
				(width 0.1524)
				(type default)
			)
			(layer "B.SilkS")
		)
		(fp_line
			(start -0.7874 0.4064)
			(end 0.7874 0.4064)
			(stroke
				(width 0.1524)
				(type default)
			)
			(layer "B.SilkS")
		)
		(fp_line
			(start -0.7874 -0.4064)
			(end -0.7874 0.4064)
			(stroke
				(width 0.1524)
				(type default)
			)
			(layer "B.SilkS")
		)
		(fp_line
			(start 0.67945 0.3048)
			(end 0.67945 -0.305054)
			(stroke
				(width 0.1)
				(type default)
			)
			(layer "B.Fab")
		)
		(fp_line
			(start 0.67945 -0.305054)
			(end 0.12065 -0.305054)
			(stroke
				(width 0.1)
				(type default)
			)
			(layer "B.Fab")
		)
		(fp_line
			(start 0.12065 0.3048)
			(end 0.67945 0.3048)
			(stroke
				(width 0.1)
				(type default)
			)
			(layer "B.Fab")
		)
		(fp_line
			(start 0.12065 0.2794)
			(end 0.12065 0.3048)
			(stroke
				(width 0.1)
				(type default)
			)
			(layer "B.Fab")
		)
		(fp_line
			(start 0.12065 -0.2794)
			(end -0.12065 -0.2794)
			(stroke
				(width 0.1)
				(type default)
			)
			(layer "B.Fab")
		)
		(fp_line
			(start 0.12065 -0.305054)
			(end 0.12065 -0.2794)
			(stroke
				(width 0.1)
				(type default)
			)
			(layer "B.Fab")
		)
		(fp_line
			(start -0.120396 0.3048)
			(end -0.120396 0.2794)
			(stroke
				(width 0.1)
				(type default)
			)
			(layer "B.Fab")
		)
		(fp_line
			(start -0.120396 0.2794)
			(end 0.12065 0.2794)
			(stroke
				(width 0.1)
				(type default)
			)
			(layer "B.Fab")
		)
		(fp_line
			(start -0.12065 -0.2794)
			(end -0.12065 -0.3048)
			(stroke
				(width 0.1)
				(type default)
			)
			(layer "B.Fab")
		)
		(fp_line
			(start -0.12065 -0.3048)
			(end -0.67945 -0.3048)
			(stroke
				(width 0.1)
				(type default)
			)
			(layer "B.Fab")
		)
		(fp_line
			(start -0.67945 0.3048)
			(end -0.120396 0.3048)
			(stroke
				(width 0.1)
				(type default)
			)
			(layer "B.Fab")
		)
		(fp_line
			(start -0.67945 -0.3048)
			(end -0.67945 0.3048)
			(stroke
				(width 0.1)
				(type default)
			)
			(layer "B.Fab")
		)
		(pad "1" smd circle
			(at 0.40005 0)
			(size 0 0)
			(layers "B.Cu" "B.Mask" "B.Paste")
			(net "SMB_9ZXL0451E_ADDR0")
		)
		(pad "2" smd circle
			(at -0.40005 0)
			(size 0 0)
			(layers "B.Cu" "B.Mask" "B.Paste")
			(net "P3V3")
		)
	)
	(footprint ""
		(layer "B.Cu")
		(at 222.212154 -192.959736 -90)
		(property "Reference" "R1027"
			(at 0 0 90)
			(layer "B.SilkS")
			(hide yes)
			(effects
				(font
					(size 1.27 1.27)
				)
				(justify mirror)
			)
		)
		(property "Value" ""
			(at 0 0 90)
			(layer "B.Fab")
			(effects
				(font
					(size 1.27 1.27)
				)
				(justify mirror)
			)
		)
		(duplicate_pad_numbers_are_jumpers no)
		(fp_line
			(start -0.7874 0.4064)
			(end 0.7874 0.4064)
			(stroke
				(width 0.1524)
				(type default)
			)
			(layer "B.SilkS")
		)
		(fp_line
			(start 0.7874 0.4064)
			(end 0.7874 -0.4064)
			(stroke
				(width 0.1524)
				(type default)
			)
			(layer "B.SilkS")
		)
		(fp_line
			(start -0.7874 -0.4064)
			(end -0.7874 0.4064)
			(stroke
				(width 0.1524)
				(type default)
			)
			(layer "B.SilkS")
		)
		(fp_line
			(start 0.7874 -0.4064)
			(end -0.7874 -0.4064)
			(stroke
				(width 0.1524)
				(type default)
			)
			(layer "B.SilkS")
		)
		(fp_line
			(start -0.67945 0.3048)
			(end -0.120396 0.3048)
			(stroke
				(width 0.1)
				(type default)
			)
			(layer "B.Fab")
		)
		(fp_line
			(start -0.120396 0.3048)
			(end -0.120396 0.2794)
			(stroke
				(width 0.1)
				(type default)
			)
			(layer "B.Fab")
		)
		(fp_line
			(start 0.12065 0.3048)
			(end 0.67945 0.3048)
			(stroke
				(width 0.1)
				(type default)
			)
			(layer "B.Fab")
		)
		(fp_line
			(start 0.67945 0.3048)
			(end 0.67945 -0.305054)
			(stroke
				(width 0.1)
				(type default)
			)
			(layer "B.Fab")
		)
		(fp_line
			(start -0.120396 0.2794)
			(end 0.12065 0.2794)
			(stroke
				(width 0.1)
				(type default)
			)
			(layer "B.Fab")
		)
		(fp_line
			(start 0.12065 0.2794)
			(end 0.12065 0.3048)
			(stroke
				(width 0.1)
				(type default)
			)
			(layer "B.Fab")
		)
		(fp_line
			(start -0.12065 -0.2794)
			(end -0.12065 -0.3048)
			(stroke
				(width 0.1)
				(type default)
			)
			(layer "B.Fab")
		)
		(fp_line
			(start 0.12065 -0.2794)
			(end -0.12065 -0.2794)
			(stroke
				(width 0.1)
				(type default)
			)
			(layer "B.Fab")
		)
		(fp_line
			(start -0.67945 -0.3048)
			(end -0.67945 0.3048)
			(stroke
				(width 0.1)
				(type default)
			)
			(layer "B.Fab")
		)
		(fp_line
			(start -0.12065 -0.3048)
			(end -0.67945 -0.3048)
			(stroke
				(width 0.1)
				(type default)
			)
			(layer "B.Fab")
		)
		(fp_line
			(start 0.12065 -0.305054)
			(end 0.12065 -0.2794)
			(stroke
				(width 0.1)
				(type default)
			)
			(layer "B.Fab")
		)
		(fp_line
			(start 0.67945 -0.305054)
			(end 0.12065 -0.305054)
			(stroke
				(width 0.1)
				(type default)
			)
			(layer "B.Fab")
		)
		(pad "1" smd circle
			(at 0.40005 0 90)
			(size 0 0)
			(layers "B.Cu" "B.Mask" "B.Paste")
			(net "SPI2_DO_BUF")
		)
		(pad "2" smd circle
			(at -0.40005 0 90)
			(size 0 0)
			(layers "B.Cu" "B.Mask" "B.Paste")
			(net "SPI_BIC1_MOSI_R2")
		)
	)
	(footprint ""
		(layer "B.Cu")
		(at 351.547684 -304.157634 180)
		(property "Reference" "PR130"
			(at 0 0 0)
			(layer "B.SilkS")
			(hide yes)
			(effects
				(font
					(size 1.27 1.27)
				)
				(justify mirror)
			)
		)
		(property "Value" ""
			(at 0 0 0)
			(layer "B.Fab")
			(effects
				(font
					(size 1.27 1.27)
				)
				(justify mirror)
			)
		)
		(duplicate_pad_numbers_are_jumpers no)
		(fp_line
			(start 0.7874 0.4064)
			(end 0.7874 -0.4064)
			(stroke
				(width 0.1524)
				(type default)
			)
			(layer "B.SilkS")
		)
		(fp_line
			(start 0.7874 -0.4064)
			(end -0.7874 -0.4064)
			(stroke
				(width 0.1524)
				(type default)
			)
			(layer "B.SilkS")
		)
		(fp_line
			(start -0.7874 0.4064)
			(end 0.7874 0.4064)
			(stroke
				(width 0.1524)
				(type default)
			)
			(layer "B.SilkS")
		)
		(fp_line
			(start -0.7874 -0.4064)
			(end -0.7874 0.4064)
			(stroke
				(width 0.1524)
				(type default)
			)
			(layer "B.SilkS")
		)
		(fp_line
			(start 0.67945 0.3048)
			(end 0.67945 -0.305054)
			(stroke
				(width 0.1)
				(type default)
			)
			(layer "B.Fab")
		)
		(fp_line
			(start 0.67945 -0.305054)
			(end 0.12065 -0.305054)
			(stroke
				(width 0.1)
				(type default)
			)
			(layer "B.Fab")
		)
		(fp_line
			(start 0.12065 0.3048)
			(end 0.67945 0.3048)
			(stroke
				(width 0.1)
				(type default)
			)
			(layer "B.Fab")
		)
		(fp_line
			(start 0.12065 0.2794)
			(end 0.12065 0.3048)
			(stroke
				(width 0.1)
				(type default)
			)
			(layer "B.Fab")
		)
		(fp_line
			(start 0.12065 -0.2794)
			(end -0.12065 -0.2794)
			(stroke
				(width 0.1)
				(type default)
			)
			(layer "B.Fab")
		)
		(fp_line
			(start 0.12065 -0.305054)
			(end 0.12065 -0.2794)
			(stroke
				(width 0.1)
				(type default)
			)
			(layer "B.Fab")
		)
		(fp_line
			(start -0.120396 0.3048)
			(end -0.120396 0.2794)
			(stroke
				(width 0.1)
				(type default)
			)
			(layer "B.Fab")
		)
		(fp_line
			(start -0.120396 0.2794)
			(end 0.12065 0.2794)
			(stroke
				(width 0.1)
				(type default)
			)
			(layer "B.Fab")
		)
		(fp_line
			(start -0.12065 -0.2794)
			(end -0.12065 -0.3048)
			(stroke
				(width 0.1)
				(type default)
			)
			(layer "B.Fab")
		)
		(fp_line
			(start -0.12065 -0.3048)
			(end -0.67945 -0.3048)
			(stroke
				(width 0.1)
				(type default)
			)
			(layer "B.Fab")
		)
		(fp_line
			(start -0.67945 0.3048)
			(end -0.120396 0.3048)
			(stroke
				(width 0.1)
				(type default)
			)
			(layer "B.Fab")
		)
		(fp_line
			(start -0.67945 -0.3048)
			(end -0.67945 0.3048)
			(stroke
				(width 0.1)
				(type default)
			)
			(layer "B.Fab")
		)
		(pad "1" smd circle
			(at 0.40005 0)
			(size 0 0)
			(layers "B.Cu" "B.Mask" "B.Paste")
			(net "SH_P0V8_PEX3_RGND3")
		)
		(pad "2" smd circle
			(at -0.40005 0)
			(size 0 0)
			(layers "B.Cu" "B.Mask" "B.Paste")
			(net "GND")
		)
	)
	(footprint ""
		(layer "B.Cu")
		(at 180.02504 -286.399732 90)
		(property "Reference" "C3159"
			(at 0 0 90)
			(layer "B.SilkS")
			(hide yes)
			(effects
				(font
					(size 1.27 1.27)
				)
				(justify mirror)
			)
		)
		(property "Value" ""
			(at 0 0 90)
			(layer "B.Fab")
			(effects
				(font
					(size 1.27 1.27)
				)
				(justify mirror)
			)
		)
		(duplicate_pad_numbers_are_jumpers no)
		(fp_line
			(start 0.299974 -0.150114)
			(end -0.299974 -0.150114)
			(stroke
				(width 0.1)
				(type default)
			)
			(layer "B.Fab")
		)
		(fp_line
			(start -0.299974 -0.150114)
			(end -0.299974 0.150114)
			(stroke
				(width 0.1)
				(type default)
			)
			(layer "B.Fab")
		)
		(fp_line
			(start 0.299974 0.150114)
			(end 0.299974 -0.150114)
			(stroke
				(width 0.1)
				(type default)
			)
			(layer "B.Fab")
		)
		(fp_line
			(start -0.299974 0.150114)
			(end 0.299974 0.150114)
			(stroke
				(width 0.1)
				(type default)
			)
			(layer "B.Fab")
		)
		(pad "1" smd rect
			(at 0.2667 0 270)
			(size 0.3048 0.381)
			(layers "B.Cu" "B.Mask" "B.Paste")
			(net "P1V25_SERDES_VDDPLL_PEX1")
		)
		(pad "2" smd rect
			(at -0.2667 0 270)
			(size 0.3048 0.381)
			(layers "B.Cu" "B.Mask" "B.Paste")
			(net "GND")
		)
	)
	(footprint ""
		(layer "B.Cu")
		(at 392.749786 -292.099746)
		(property "Reference" "C3525"
			(at 0 0 0)
			(layer "B.SilkS")
			(hide yes)
			(effects
				(font
					(size 1.27 1.27)
				)
				(justify mirror)
			)
		)
		(property "Value" ""
			(at 0 0 0)
			(layer "B.Fab")
			(effects
				(font
					(size 1.27 1.27)
				)
				(justify mirror)
			)
		)
		(duplicate_pad_numbers_are_jumpers no)
		(fp_line
			(start -0.299974 -0.150114)
			(end -0.299974 0.150114)
			(stroke
				(width 0.1)
				(type default)
			)
			(layer "B.Fab")
		)
		(fp_line
			(start -0.299974 0.150114)
			(end 0.299974 0.150114)
			(stroke
				(width 0.1)
				(type default)
			)
			(layer "B.Fab")
		)
		(fp_line
			(start 0.299974 -0.150114)
			(end -0.299974 -0.150114)
			(stroke
				(width 0.1)
				(type default)
			)
			(layer "B.Fab")
		)
		(fp_line
			(start 0.299974 0.150114)
			(end 0.299974 -0.150114)
			(stroke
				(width 0.1)
				(type default)
			)
			(layer "B.Fab")
		)
		(pad "1" smd rect
			(at 0.2667 0 180)
			(size 0.3048 0.381)
			(layers "B.Cu" "B.Mask" "B.Paste")
			(net "P1V8_PEX")
		)
		(pad "2" smd rect
			(at -0.2667 0 180)
			(size 0.3048 0.381)
			(layers "B.Cu" "B.Mask" "B.Paste")
			(net "GND")
		)
	)
)
